(kicad_pcb
	(version 20260206)
	(generator "pcbnew")
	(generator_version "10.0")
	(general
		(thickness 1.6)
		(legacy_teardrops no)
	)
	(paper "A4")
	(title_block
		(title "peb — Lightning_PEB_BRD.brd")
		(comment 1 "Lightning (Wiwynn / Facebook NVMe JBOF) / footprint 1445 of 2563 (U1), pads 1051-1168 of 1311")
	)
	(layers
		(0 "F.Cu" signal "TOP")
		(4 "In1.Cu" signal "L2GND")
		(6 "In2.Cu" signal "L3")
		(8 "In3.Cu" signal "L4VCC")
		(10 "In4.Cu" signal "L5VCC")
		(12 "In5.Cu" signal "L6")
		(14 "In6.Cu" signal "L7GND")
		(2 "B.Cu" signal "BOTTOM")
		(9 "F.Adhes" user "F.Adhesive")
		(11 "B.Adhes" user "B.Adhesive")
		(13 "F.Paste" user "Package Geometry/Pastemask Top")
		(15 "B.Paste" user "Package Geometry/Pastemask Bottom")
		(5 "F.SilkS" user "Ref Des/Silkscreen Top")
		(7 "B.SilkS" user "Ref Des/Silkscreen Bottom")
		(1 "F.Mask" user "Board Geometry/Soldermask Top")
		(3 "B.Mask" user "Board Geometry/Soldermask Bottom")
		(17 "Dwgs.User" user "User.Drawings")
		(19 "Cmts.User" user "User.Comments")
		(21 "Eco1.User" user "User.Eco1")
		(23 "Eco2.User" user "User.Eco2")
		(25 "Edge.Cuts" user "Board Geometry/Outline")
		(27 "Margin" user)
		(31 "F.CrtYd" user "Package Geometry/Place Bound Top")
		(29 "B.CrtYd" user "Package Geometry/Place Bound Bottom")
		(35 "F.Fab" user "Ref Des/Assembly Top")
		(33 "B.Fab" user "Ref Des/Assembly Bottom")
	)
	(footprint ""
		(layer "F.Cu")
		(at 240.599976 -47.999904 -90)
		(property "Reference" "U1"
			(at 0 0 270)
			(layer "F.SilkS")
			(hide yes)
			(effects
				(font
					(size 1.27 1.27)
				)
			)
		)
		(property "Value" "PM8546A-FEIP-GP"
			(at -25.785064 -6.40334 270)
			(unlocked yes)
			(layer "F.Fab")
			(hide yes)
			(effects
				(font
					(size 1.016 1.016)
					(thickness 0.1524)
				)
			)
		)
		(property "Device Type" "BGA1311C37D5H134"
			(at -25.785064 -7.92734 270)
			(unlocked yes)
			(layer "F.Fab")
			(hide yes)
			(effects
				(font
					(size 1.016 1.016)
					(thickness 0.1524)
				)
			)
		)
		(duplicate_pad_numbers_are_jumpers no)
		(pad "N30" smd circle
			(at 10.999978 -5.999988 270)
			(size 0.4572 0.4572)
			(layers "F.Cu" "F.Mask" "F.Paste")
			(net "TWI_SRST#7")
		)
		(pad "N31" smd circle
			(at 11.999976 -5.999988 270)
			(size 0.4572 0.4572)
			(layers "F.Cu" "F.Mask" "F.Paste")
			(net "IOEXP_INT#_2")
		)
		(pad "N32" smd circle
			(at 12.999974 -5.999988 270)
			(size 0.4572 0.4572)
			(layers "F.Cu" "F.Mask" "F.Paste")
			(net "TWI_SCL10")
		)
		(pad "N33" smd circle
			(at 13.999972 -5.999988 270)
			(size 0.4572 0.4572)
			(layers "F.Cu" "F.Mask" "F.Paste")
			(net "TWI_SDA10")
		)
		(pad "N34" smd circle
			(at 14.99997 -5.999988 270)
			(size 0.4572 0.4572)
			(layers "F.Cu" "F.Mask" "F.Paste")
			(net "DUT_VDDO")
		)
		(pad "N35" smd circle
			(at 15.999968 -5.999988 270)
			(size 0.4572 0.4572)
			(layers "F.Cu" "F.Mask" "F.Paste")
			(net "GND")
		)
		(pad "N36" smd circle
			(at 16.999966 -5.999988 270)
			(size 0.4572 0.4572)
			(layers "F.Cu" "F.Mask" "F.Paste")
			(net "PCIE_RX_P4")
		)
		(pad "N37" smd circle
			(at 17.999964 -5.999988 270)
			(size 0.4572 0.4572)
			(layers "F.Cu" "F.Mask" "F.Paste")
			(net "PCIE_RX_N4")
		)
		(pad "P2" smd circle
			(at -16.999966 -4.99999 270)
			(size 0.4572 0.4572)
			(layers "F.Cu" "F.Mask" "F.Paste")
			(net "PCIE_TX_CAP_N43")
		)
		(pad "P3" smd circle
			(at -15.999968 -4.99999 270)
			(size 0.4572 0.4572)
			(layers "F.Cu" "F.Mask" "F.Paste")
			(net "PCIE_TX_CAP_P43")
		)
		(pad "P4" smd circle
			(at -14.99997 -4.99999 270)
			(size 0.4572 0.4572)
			(layers "F.Cu" "F.Mask" "F.Paste")
			(net "GND")
		)
		(pad "P5" smd circle
			(at -13.999972 -4.99999 270)
			(size 0.4572 0.4572)
			(layers "F.Cu" "F.Mask" "F.Paste")
			(net "PCIE_RX_N43")
		)
		(pad "P6" smd circle
			(at -12.999974 -4.99999 270)
			(size 0.4572 0.4572)
			(layers "F.Cu" "F.Mask" "F.Paste")
			(net "PCIE_RX_P43")
		)
		(pad "P7" smd circle
			(at -11.999976 -4.99999 270)
			(size 0.4572 0.4572)
			(layers "F.Cu" "F.Mask" "F.Paste")
			(net "GND")
		)
		(pad "P8" smd circle
			(at -10.999978 -4.99999 270)
			(size 0.4572 0.4572)
			(layers "F.Cu" "F.Mask" "F.Paste")
			(net "DUT_AVD_TX")
		)
		(pad "P9" smd circle
			(at -9.99998 -4.99999 270)
			(size 0.4572 0.4572)
			(layers "F.Cu" "F.Mask" "F.Paste")
			(net "GND")
		)
		(pad "P10" smd circle
			(at -8.999982 -4.99999 270)
			(size 0.4572 0.4572)
			(layers "F.Cu" "F.Mask" "F.Paste")
			(net "DUT_AVD_TX")
		)
		(pad "P11" smd circle
			(at -7.999984 -4.99999 270)
			(size 0.4572 0.4572)
			(layers "F.Cu" "F.Mask" "F.Paste")
			(net "GND")
		)
		(pad "P12" smd circle
			(at -6.999986 -4.99999 270)
			(size 0.4572 0.4572)
			(layers "F.Cu" "F.Mask" "F.Paste")
			(net "GND")
		)
		(pad "P13" smd circle
			(at -5.999988 -4.99999 270)
			(size 0.4572 0.4572)
			(layers "F.Cu" "F.Mask" "F.Paste")
			(net "DUT_VDD")
		)
		(pad "P14" smd circle
			(at -4.99999 -4.99999 270)
			(size 0.4572 0.4572)
			(layers "F.Cu" "F.Mask" "F.Paste")
			(net "GND")
		)
		(pad "P15" smd circle
			(at -3.999992 -4.99999 270)
			(size 0.4572 0.4572)
			(layers "F.Cu" "F.Mask" "F.Paste")
			(net "DUT_VDD")
		)
		(pad "P16" smd circle
			(at -2.999994 -4.99999 270)
			(size 0.4572 0.4572)
			(layers "F.Cu" "F.Mask" "F.Paste")
			(net "GND")
		)
		(pad "P17" smd circle
			(at -1.999996 -4.99999 270)
			(size 0.4572 0.4572)
			(layers "F.Cu" "F.Mask" "F.Paste")
			(net "DUT_VDD")
		)
		(pad "P18" smd circle
			(at -0.999998 -4.99999 270)
			(size 0.4572 0.4572)
			(layers "F.Cu" "F.Mask" "F.Paste")
			(net "GND")
		)
		(pad "P19" smd circle
			(at 0 -4.99999 270)
			(size 0.4572 0.4572)
			(layers "F.Cu" "F.Mask" "F.Paste")
			(net "DUT_VDD")
		)
		(pad "P20" smd circle
			(at 0.999998 -4.99999 270)
			(size 0.4572 0.4572)
			(layers "F.Cu" "F.Mask" "F.Paste")
			(net "GND")
		)
		(pad "P21" smd circle
			(at 1.999996 -4.99999 270)
			(size 0.4572 0.4572)
			(layers "F.Cu" "F.Mask" "F.Paste")
			(net "DUT_VDD")
		)
		(pad "P22" smd circle
			(at 2.999994 -4.99999 270)
			(size 0.4572 0.4572)
			(layers "F.Cu" "F.Mask" "F.Paste")
			(net "GND")
		)
		(pad "P23" smd circle
			(at 3.999992 -4.99999 270)
			(size 0.4572 0.4572)
			(layers "F.Cu" "F.Mask" "F.Paste")
			(net "DUT_VDD")
		)
		(pad "P24" smd circle
			(at 4.99999 -4.99999 270)
			(size 0.4572 0.4572)
			(layers "F.Cu" "F.Mask" "F.Paste")
			(net "GND")
		)
		(pad "P25" smd circle
			(at 5.999988 -4.99999 270)
			(size 0.4572 0.4572)
			(layers "F.Cu" "F.Mask" "F.Paste")
			(net "DUT_VDD")
		)
		(pad "P26" smd circle
			(at 6.999986 -4.99999 270)
			(size 0.4572 0.4572)
			(layers "F.Cu" "F.Mask" "F.Paste")
			(net "GND")
		)
		(pad "P27" smd circle
			(at 7.999984 -4.99999 270)
			(size 0.4572 0.4572)
			(layers "F.Cu" "F.Mask" "F.Paste")
			(net "VSS_572")
		)
		(pad "P28" smd circle
			(at 8.999982 -4.99999 270)
			(size 0.4572 0.4572)
			(layers "F.Cu" "F.Mask" "F.Paste")
			(net "DUT_VDDO")
		)
		(pad "P29" smd circle
			(at 9.99998 -4.99999 270)
			(size 0.4572 0.4572)
			(layers "F.Cu" "F.Mask" "F.Paste")
			(net "TWI_SCL3")
		)
		(pad "P30" smd circle
			(at 10.999978 -4.99999 270)
			(size 0.4572 0.4572)
			(layers "F.Cu" "F.Mask" "F.Paste")
			(net "TWI_SRST#3")
		)
		(pad "P31" smd circle
			(at 11.999976 -4.99999 270)
			(size 0.4572 0.4572)
			(layers "F.Cu" "F.Mask" "F.Paste")
			(net "GND")
		)
		(pad "P32" smd circle
			(at 12.999974 -4.99999 270)
			(size 0.4572 0.4572)
			(layers "F.Cu" "F.Mask" "F.Paste")
			(net "TWI_SDA3")
		)
		(pad "P33" smd circle
			(at 13.999972 -4.99999 270)
			(size 0.4572 0.4572)
			(layers "F.Cu" "F.Mask" "F.Paste")
			(net "TWI_SRST#4")
		)
		(pad "P34" smd circle
			(at 14.99997 -4.99999 270)
			(size 0.4572 0.4572)
			(layers "F.Cu" "F.Mask" "F.Paste")
			(net "GND")
		)
		(pad "P35" smd circle
			(at 15.999968 -4.99999 270)
			(size 0.4572 0.4572)
			(layers "F.Cu" "F.Mask" "F.Paste")
			(net "PCIE_RX_P3")
		)
		(pad "P36" smd circle
			(at 16.999966 -4.99999 270)
			(size 0.4572 0.4572)
			(layers "F.Cu" "F.Mask" "F.Paste")
			(net "PCIE_RX_N3")
		)
		(pad "R1" smd circle
			(at -17.999964 -3.999992 270)
			(size 0.4572 0.4572)
			(layers "F.Cu" "F.Mask" "F.Paste")
			(net "PCIE_TX_CAP_N44")
		)
		(pad "R2" smd circle
			(at -16.999966 -3.999992 270)
			(size 0.4572 0.4572)
			(layers "F.Cu" "F.Mask" "F.Paste")
			(net "PCIE_TX_CAP_P44")
		)
		(pad "R3" smd circle
			(at -15.999968 -3.999992 270)
			(size 0.4572 0.4572)
			(layers "F.Cu" "F.Mask" "F.Paste")
			(net "GND")
		)
		(pad "R4" smd circle
			(at -14.99997 -3.999992 270)
			(size 0.4572 0.4572)
			(layers "F.Cu" "F.Mask" "F.Paste")
			(net "PCIE_RX_N44")
		)
		(pad "R5" smd circle
			(at -13.999972 -3.999992 270)
			(size 0.4572 0.4572)
			(layers "F.Cu" "F.Mask" "F.Paste")
			(net "PCIE_RX_P44")
		)
		(pad "R6" smd circle
			(at -12.999974 -3.999992 270)
			(size 0.4572 0.4572)
			(layers "F.Cu" "F.Mask" "F.Paste")
			(net "GND")
		)
		(pad "R7" smd circle
			(at -11.999976 -3.999992 270)
			(size 0.4572 0.4572)
			(layers "F.Cu" "F.Mask" "F.Paste")
			(net "DUT_AVD_TX")
		)
		(pad "R8" smd circle
			(at -10.999978 -3.999992 270)
			(size 0.4572 0.4572)
			(layers "F.Cu" "F.Mask" "F.Paste")
			(net "GND")
		)
		(pad "R9" smd circle
			(at -9.99998 -3.999992 270)
			(size 0.4572 0.4572)
			(layers "F.Cu" "F.Mask" "F.Paste")
			(net "DUT_AVD_TX")
		)
		(pad "R10" smd circle
			(at -8.999982 -3.999992 270)
			(size 0.4572 0.4572)
			(layers "F.Cu" "F.Mask" "F.Paste")
			(net "GND")
		)
		(pad "R11" smd circle
			(at -7.999984 -3.999992 270)
			(size 0.4572 0.4572)
			(layers "F.Cu" "F.Mask" "F.Paste")
			(net "DUT_AVD_TX")
		)
		(pad "R12" smd circle
			(at -6.999986 -3.999992 270)
			(size 0.4572 0.4572)
			(layers "F.Cu" "F.Mask" "F.Paste")
			(net "GND")
		)
		(pad "R13" smd circle
			(at -5.999988 -3.999992 270)
			(size 0.4572 0.4572)
			(layers "F.Cu" "F.Mask" "F.Paste")
			(net "GND")
		)
		(pad "R14" smd circle
			(at -4.99999 -3.999992 270)
			(size 0.4572 0.4572)
			(layers "F.Cu" "F.Mask" "F.Paste")
			(net "DUT_VDD")
		)
		(pad "R15" smd circle
			(at -3.999992 -3.999992 270)
			(size 0.4572 0.4572)
			(layers "F.Cu" "F.Mask" "F.Paste")
			(net "GND")
		)
		(pad "R16" smd circle
			(at -2.999994 -3.999992 270)
			(size 0.4572 0.4572)
			(layers "F.Cu" "F.Mask" "F.Paste")
			(net "DUT_VDD")
		)
		(pad "R17" smd circle
			(at -1.999996 -3.999992 270)
			(size 0.4572 0.4572)
			(layers "F.Cu" "F.Mask" "F.Paste")
			(net "GND")
		)
		(pad "R18" smd circle
			(at -0.999998 -3.999992 270)
			(size 0.4572 0.4572)
			(layers "F.Cu" "F.Mask" "F.Paste")
			(net "DUT_VDD")
		)
		(pad "R19" smd circle
			(at 0 -3.999992 270)
			(size 0.4572 0.4572)
			(layers "F.Cu" "F.Mask" "F.Paste")
			(net "GND")
		)
		(pad "R20" smd circle
			(at 0.999998 -3.999992 270)
			(size 0.4572 0.4572)
			(layers "F.Cu" "F.Mask" "F.Paste")
			(net "DUT_VDD")
		)
		(pad "R21" smd circle
			(at 1.999996 -3.999992 270)
			(size 0.4572 0.4572)
			(layers "F.Cu" "F.Mask" "F.Paste")
			(net "GND")
		)
		(pad "R22" smd circle
			(at 2.999994 -3.999992 270)
			(size 0.4572 0.4572)
			(layers "F.Cu" "F.Mask" "F.Paste")
			(net "DUT_VDD")
		)
		(pad "R23" smd circle
			(at 3.999992 -3.999992 270)
			(size 0.4572 0.4572)
			(layers "F.Cu" "F.Mask" "F.Paste")
			(net "GND")
		)
		(pad "R24" smd circle
			(at 4.99999 -3.999992 270)
			(size 0.4572 0.4572)
			(layers "F.Cu" "F.Mask" "F.Paste")
			(net "DUT_VDD")
		)
		(pad "R25" smd circle
			(at 5.999988 -3.999992 270)
			(size 0.4572 0.4572)
			(layers "F.Cu" "F.Mask" "F.Paste")
			(net "GND")
		)
		(pad "R26" smd circle
			(at 6.999986 -3.999992 270)
			(size 0.4572 0.4572)
			(layers "F.Cu" "F.Mask" "F.Paste")
			(net "DUT_VDDO")
		)
		(pad "R27" smd circle
			(at 7.999984 -3.999992 270)
			(size 0.4572 0.4572)
			(layers "F.Cu" "F.Mask" "F.Paste")
			(net "TWI_SCL4")
		)
		(pad "R28" smd circle
			(at 8.999982 -3.999992 270)
			(size 0.4572 0.4572)
			(layers "F.Cu" "F.Mask" "F.Paste")
			(net "TWI_SDA4")
		)
		(pad "R29" smd circle
			(at 9.99998 -3.999992 270)
			(size 0.4572 0.4572)
			(layers "F.Cu" "F.Mask" "F.Paste")
			(net "TPIN")
		)
		(pad "R30" smd circle
			(at 10.999978 -3.999992 270)
			(size 0.4572 0.4572)
			(layers "F.Cu" "F.Mask" "F.Paste")
			(net "PM8536_HB")
		)
		(pad "R31" smd circle
			(at 11.999976 -3.999992 270)
			(size 0.4572 0.4572)
			(layers "F.Cu" "F.Mask" "F.Paste")
			(net "UART_USOUT")
		)
		(pad "R32" smd circle
			(at 12.999974 -3.999992 270)
			(size 0.4572 0.4572)
			(layers "F.Cu" "F.Mask" "F.Paste")
			(net "UART_USIN")
		)
		(pad "R33" smd circle
			(at 13.999972 -3.999992 270)
			(size 0.4572 0.4572)
			(layers "F.Cu" "F.Mask" "F.Paste")
			(net "LBI_DATA_0")
		)
		(pad "R34" smd circle
			(at 14.99997 -3.999992 270)
			(size 0.4572 0.4572)
			(layers "F.Cu" "F.Mask" "F.Paste")
			(net "DUT_VDDO")
		)
		(pad "R35" smd circle
			(at 15.999968 -3.999992 270)
			(size 0.4572 0.4572)
			(layers "F.Cu" "F.Mask" "F.Paste")
			(net "GND")
		)
		(pad "R36" smd circle
			(at 16.999966 -3.999992 270)
			(size 0.4572 0.4572)
			(layers "F.Cu" "F.Mask" "F.Paste")
			(net "PCIE_RX_P2")
		)
		(pad "R37" smd circle
			(at 17.999964 -3.999992 270)
			(size 0.4572 0.4572)
			(layers "F.Cu" "F.Mask" "F.Paste")
			(net "PCIE_RX_N2")
		)
		(pad "T2" smd circle
			(at -16.999966 -2.999994 270)
			(size 0.4572 0.4572)
			(layers "F.Cu" "F.Mask" "F.Paste")
			(net "PCIE_TX_CAP_N45")
		)
		(pad "T3" smd circle
			(at -15.999968 -2.999994 270)
			(size 0.4572 0.4572)
			(layers "F.Cu" "F.Mask" "F.Paste")
			(net "PCIE_TX_CAP_P45")
		)
		(pad "T4" smd circle
			(at -14.99997 -2.999994 270)
			(size 0.4572 0.4572)
			(layers "F.Cu" "F.Mask" "F.Paste")
			(net "GND")
		)
		(pad "T5" smd circle
			(at -13.999972 -2.999994 270)
			(size 0.4572 0.4572)
			(layers "F.Cu" "F.Mask" "F.Paste")
			(net "PCIE_RX_N45")
		)
		(pad "T6" smd circle
			(at -12.999974 -2.999994 270)
			(size 0.4572 0.4572)
			(layers "F.Cu" "F.Mask" "F.Paste")
			(net "PCIE_RX_P45")
		)
		(pad "T7" smd circle
			(at -11.999976 -2.999994 270)
			(size 0.4572 0.4572)
			(layers "F.Cu" "F.Mask" "F.Paste")
			(net "GND")
		)
		(pad "T8" smd circle
			(at -10.999978 -2.999994 270)
			(size 0.4572 0.4572)
			(layers "F.Cu" "F.Mask" "F.Paste")
			(net "DUT_AVD_TX")
		)
		(pad "T9" smd circle
			(at -9.99998 -2.999994 270)
			(size 0.4572 0.4572)
			(layers "F.Cu" "F.Mask" "F.Paste")
			(net "GND")
		)
		(pad "T10" smd circle
			(at -8.999982 -2.999994 270)
			(size 0.4572 0.4572)
			(layers "F.Cu" "F.Mask" "F.Paste")
			(net "DUT_AVD_TX")
		)
		(pad "T11" smd circle
			(at -7.999984 -2.999994 270)
			(size 0.4572 0.4572)
			(layers "F.Cu" "F.Mask" "F.Paste")
			(net "GND")
		)
		(pad "T12" smd circle
			(at -6.999986 -2.999994 270)
			(size 0.4572 0.4572)
			(layers "F.Cu" "F.Mask" "F.Paste")
			(net "GND")
		)
		(pad "T13" smd circle
			(at -5.999988 -2.999994 270)
			(size 0.4572 0.4572)
			(layers "F.Cu" "F.Mask" "F.Paste")
			(net "DUT_VDD")
		)
		(pad "T14" smd circle
			(at -4.99999 -2.999994 270)
			(size 0.4572 0.4572)
			(layers "F.Cu" "F.Mask" "F.Paste")
			(net "GND")
		)
		(pad "T15" smd circle
			(at -3.999992 -2.999994 270)
			(size 0.4572 0.4572)
			(layers "F.Cu" "F.Mask" "F.Paste")
			(net "DUT_VDD")
		)
		(pad "T16" smd circle
			(at -2.999994 -2.999994 270)
			(size 0.4572 0.4572)
			(layers "F.Cu" "F.Mask" "F.Paste")
			(net "GND")
		)
		(pad "T17" smd circle
			(at -1.999996 -2.999994 270)
			(size 0.4572 0.4572)
			(layers "F.Cu" "F.Mask" "F.Paste")
			(net "DUT_VDD")
		)
		(pad "T18" smd circle
			(at -0.999998 -2.999994 270)
			(size 0.4572 0.4572)
			(layers "F.Cu" "F.Mask" "F.Paste")
			(net "GND")
		)
		(pad "T19" smd circle
			(at 0 -2.999994 270)
			(size 0.4572 0.4572)
			(layers "F.Cu" "F.Mask" "F.Paste")
			(net "DUT_VDD")
		)
		(pad "T20" smd circle
			(at 0.999998 -2.999994 270)
			(size 0.4572 0.4572)
			(layers "F.Cu" "F.Mask" "F.Paste")
			(net "GND")
		)
		(pad "T21" smd circle
			(at 1.999996 -2.999994 270)
			(size 0.4572 0.4572)
			(layers "F.Cu" "F.Mask" "F.Paste")
			(net "DUT_VDD")
		)
		(pad "T22" smd circle
			(at 2.999994 -2.999994 270)
			(size 0.4572 0.4572)
			(layers "F.Cu" "F.Mask" "F.Paste")
			(net "GND")
		)
		(pad "T23" smd circle
			(at 3.999992 -2.999994 270)
			(size 0.4572 0.4572)
			(layers "F.Cu" "F.Mask" "F.Paste")
			(net "DUT_VDD")
		)
		(pad "T24" smd circle
			(at 4.99999 -2.999994 270)
			(size 0.4572 0.4572)
			(layers "F.Cu" "F.Mask" "F.Paste")
			(net "GND")
		)
		(pad "T25" smd circle
			(at 5.999988 -2.999994 270)
			(size 0.4572 0.4572)
			(layers "F.Cu" "F.Mask" "F.Paste")
			(net "DUT_VDD")
		)
		(pad "T26" smd circle
			(at 6.999986 -2.999994 270)
			(size 0.4572 0.4572)
			(layers "F.Cu" "F.Mask" "F.Paste")
			(net "GND")
		)
		(pad "T27" smd circle
			(at 7.999984 -2.999994 270)
			(size 0.4572 0.4572)
			(layers "F.Cu" "F.Mask" "F.Paste")
			(net "RS232_UCTSB0")
		)
		(pad "T28" smd circle
			(at 8.999982 -2.999994 270)
			(size 0.4572 0.4572)
			(layers "F.Cu" "F.Mask" "F.Paste")
			(net "RS232_URTSB0")
		)
		(pad "T29" smd circle
			(at 9.99998 -2.999994 270)
			(size 0.4572 0.4572)
			(layers "F.Cu" "F.Mask" "F.Paste")
			(net "GND")
		)
		(pad "T30" smd circle
			(at 10.999978 -2.999994 270)
			(size 0.4572 0.4572)
			(layers "F.Cu" "F.Mask" "F.Paste")
			(net "LBI_DATA_1")
		)
		(pad "T31" smd circle
			(at 11.999976 -2.999994 270)
			(size 0.4572 0.4572)
			(layers "F.Cu" "F.Mask" "F.Paste")
			(net "LBI_DATA_2")
		)
		(pad "T32" smd circle
			(at 12.999974 -2.999994 270)
			(size 0.4572 0.4572)
			(layers "F.Cu" "F.Mask" "F.Paste")
			(net "LBI_DATA_4")
		)
		(pad "T33" smd circle
			(at 13.999972 -2.999994 270)
			(size 0.4572 0.4572)
			(layers "F.Cu" "F.Mask" "F.Paste")
			(net "LBI_DATA_3")
		)
		(pad "T34" smd circle
			(at 14.99997 -2.999994 270)
			(size 0.4572 0.4572)
			(layers "F.Cu" "F.Mask" "F.Paste")
			(net "GND")
		)
		(pad "T35" smd circle
			(at 15.999968 -2.999994 270)
			(size 0.4572 0.4572)
			(layers "F.Cu" "F.Mask" "F.Paste")
			(net "PCIE_RX_P1")
		)
		(pad "T36" smd circle
			(at 16.999966 -2.999994 270)
			(size 0.4572 0.4572)
			(layers "F.Cu" "F.Mask" "F.Paste")
			(net "PCIE_RX_N1")
		)
		(pad "U1" smd circle
			(at -17.999964 -1.999996 270)
			(size 0.4572 0.4572)
			(layers "F.Cu" "F.Mask" "F.Paste")
			(net "PCIE_TX_CAP_N46")
		)
		(pad "U2" smd circle
			(at -16.999966 -1.999996 270)
			(size 0.4572 0.4572)
			(layers "F.Cu" "F.Mask" "F.Paste")
			(net "PCIE_TX_CAP_P46")
		)
		(pad "U3" smd circle
			(at -15.999968 -1.999996 270)
			(size 0.4572 0.4572)
			(layers "F.Cu" "F.Mask" "F.Paste")
			(net "GND")
		)
	)
)
